0.00100 T01
0.01000 T02
0.01200 T03
0.01400 T04
0.01417 T05
0.01600 T06
0.02000 T07
0.02913 T08
0.03500 T09
0.03700 T010
0.04015 T011
0.05300 T012
0.07100 T013
0.08600 T014
0.09900 T015
0.11100 T016
0.11900 T017
0.12600 T018
0.13800 T019
0.14000 T020
0.40400 T021
